# BASEBOARD_FAB2 (Tioga Pass) — schematic netlist excerpt (pin names and nets, part order shuffled) for the footprints in the layout excerpt that follows; sources: Cadence DE-HDL packaged netlist, KiCad conversion of Wiwynn_Tioga_Pass_MB.brd

R2U49  RES  0.0 5% EMPTY  pkg 0402  page 152 : A = H_CPU0_MEMABC_MEMHOT_G_PCH_N ; B = H_CPU0_MEMABC_MEMHOT_LVT3_K_N
C2T31  CAP_A  1.0UF 6.3V 10% X6S  pkg 0402V  page 101 : A = P3V3_STBY_MNG_RGMII ; B = GND
C2R3  CAP_A  0.1UF 16V 10% X7R  pkg 0402V  page 192 : A = P3V3_STBY ; B = GND

(kicad_pcb
	(version 20260206)
	(generator "pcbnew")
	(generator_version "10.0")
	(general
		(thickness 1.6)
		(legacy_teardrops no)
	)
	(paper "A4")
	(title_block
		(title "Wiwynn_Tioga_Pass_MB.brd")
		(comment 1 "Tioga Pass / footprints 3059-3061 of 4770")
	)
	(layers
		(0 "F.Cu" signal "TOP")
		(4 "In1.Cu" signal "L2GND")
		(6 "In2.Cu" signal "L3")
		(8 "In3.Cu" signal "L4GND")
		(10 "In4.Cu" signal "L5")
		(12 "In5.Cu" signal "L6GND")
		(14 "In6.Cu" signal "L7VCC")
		(16 "In7.Cu" signal "L8VCC")
		(18 "In8.Cu" signal "L9GND")
		(20 "In9.Cu" signal "L10")
		(22 "In10.Cu" signal "L11GND")
		(24 "In11.Cu" signal "L12")
		(26 "In12.Cu" signal "L13GND")
		(2 "B.Cu" signal "BOTTOM")
		(9 "F.Adhes" user "F.Adhesive")
		(11 "B.Adhes" user "B.Adhesive")
		(13 "F.Paste" user "Package Geometry/Pastemask Top")
		(15 "B.Paste" user "Package Geometry/Pastemask Bottom")
		(5 "F.SilkS" user "Ref Des/Silkscreen Top")
		(7 "B.SilkS" user "Ref Des/Silkscreen Bottom")
		(1 "F.Mask" user "Board Geometry/Soldermask Top")
		(3 "B.Mask" user "Board Geometry/Soldermask Bottom")
		(17 "Dwgs.User" user "User.Drawings")
		(19 "Cmts.User" user "User.Comments")
		(21 "Eco1.User" user "User.Eco1")
		(23 "Eco2.User" user "User.Eco2")
		(25 "Edge.Cuts" user "Board Geometry/Outline")
		(27 "Margin" user)
		(31 "F.CrtYd" user "Package Geometry/Place Bound Top")
		(29 "B.CrtYd" user "Package Geometry/Place Bound Bottom")
		(35 "F.Fab" user "Ref Des/Assembly Top")
		(33 "B.Fab" user "Ref Des/Assembly Bottom")
	)
	(footprint ""
		(layer "B.Cu")
		(at 368.346228 -70.696074)
		(property "Reference" "C2R3"
			(at 0 0 0)
			(layer "B.SilkS")
			(hide yes)
			(effects
				(font
					(size 1.27 1.27)
				)
				(justify mirror)
			)
		)
		(property "Value" ""
			(at 0 0 0)
			(layer "B.Fab")
			(effects
				(font
					(size 1.27 1.27)
				)
				(justify mirror)
			)
		)
		(duplicate_pad_numbers_are_jumpers no)
		(fp_rect
			(start 0.2794 0.9144)
			(end -0.2794 -0.1143)
			(stroke
				(width 0)
				(type default)
			)
			(fill no)
			(layer "B.CrtYd")
		)
		(fp_line
			(start -0.2794 -0.1143)
			(end -0.2794 0.9144)
			(stroke
				(width 0.1)
				(type default)
			)
			(layer "B.Fab")
		)
		(fp_line
			(start -0.2794 0.9144)
			(end 0.2794 0.9144)
			(stroke
				(width 0.1)
				(type default)
			)
			(layer "B.Fab")
		)
		(fp_line
			(start 0.2794 -0.1143)
			(end -0.2794 -0.1143)
			(stroke
				(width 0.1)
				(type default)
			)
			(layer "B.Fab")
		)
		(fp_line
			(start 0.2794 0.9144)
			(end 0.2794 -0.1143)
			(stroke
				(width 0.1)
				(type default)
			)
			(layer "B.Fab")
		)
		(pad "1" smd custom
			(at 0 0 270)
			(size 0.10414 0.10414)
			(layers "B.Cu" "B.Mask" "B.Paste")
			(net "P3V3_STBY")
			(options
				(clearance outline)
				(anchor circle)
			)
			(primitives
				(gr_poly
					(pts
						(xy -0.20828 -0.08636) (xy -0.20828 0.08636) (xy -0.08636 0.20828) (xy 0.086614 0.20828) (xy 0.20828 0.086614)
						(xy 0.20828 -0.08636) (xy 0.08636 -0.20828) (xy -0.08636 -0.20828)
					)
					(width 0)
					(fill yes)
				)
			)
		)
		(pad "2" smd custom
			(at 0 0.8001 270)
			(size 0.10414 0.10414)
			(layers "B.Cu" "B.Mask" "B.Paste")
			(net "GND")
			(options
				(clearance outline)
				(anchor circle)
			)
			(primitives
				(gr_poly
					(pts
						(xy -0.20828 -0.08636) (xy -0.20828 0.08636) (xy -0.08636 0.20828) (xy 0.086614 0.20828) (xy 0.20828 0.086614)
						(xy 0.20828 -0.08636) (xy 0.08636 -0.20828) (xy -0.08636 -0.20828)
					)
					(width 0)
					(fill yes)
				)
			)
		)
		(zone
			(layer "B.Cu")
			(hatch none 0.5)
			(connect_pads
				(clearance 0)
			)
			(min_thickness 0.25)
			(keepout
				(tracks allowed)
				(vias not_allowed)
				(pads allowed)
				(copperpour not_allowed)
				(footprints allowed)
			)
			(placement
				(enabled no)
				(sheetname "")
			)
			(fill
				(thermal_gap 0.5)
				(thermal_bridge_width 0.5)
				(island_removal_mode 0)
			)
			(polygon
				(pts
					(xy 368.433858 -70.486524) (xy 368.433858 -70.105524) (xy 368.258598 -70.105524) (xy 368.258344 -70.486524)
				)
			)
		)
		(zone
			(layer "B.Cu")
			(hatch none 0.5)
			(connect_pads
				(clearance 0)
			)
			(min_thickness 0.25)
			(keepout
				(tracks not_allowed)
				(vias allowed)
				(pads allowed)
				(copperpour not_allowed)
				(footprints allowed)
			)
			(placement
				(enabled no)
				(sheetname "")
			)
			(fill
				(thermal_gap 0.5)
				(thermal_bridge_width 0.5)
				(island_removal_mode 0)
			)
			(polygon
				(pts
					(xy 368.433858 -70.486524) (xy 368.433858 -70.105524) (xy 368.258598 -70.105524) (xy 368.258344 -70.486524)
				)
			)
		)
	)
	(footprint ""
		(layer "B.Cu")
		(at 474.41866 -30.85592 90)
		(property "Reference" "C2T31"
			(at 0 0 90)
			(layer "B.SilkS")
			(hide yes)
			(effects
				(font
					(size 1.27 1.27)
				)
				(justify mirror)
			)
		)
		(property "Value" ""
			(at 0 0 90)
			(layer "B.Fab")
			(effects
				(font
					(size 1.27 1.27)
				)
				(justify mirror)
			)
		)
		(duplicate_pad_numbers_are_jumpers no)
		(fp_poly
			(pts
				(xy -0.3048 -0.1016) (xy -0.3048 0.9906) (xy 0.3048 0.9906) (xy 0.3048 -0.1016)
			)
			(stroke
				(width 0)
				(type default)
			)
			(fill no)
			(layer "B.CrtYd")
		)
		(fp_line
			(start 0.3048 -0.1016)
			(end 0.3048 0.9906)
			(stroke
				(width 0.1)
				(type default)
			)
			(layer "B.Fab")
		)
		(fp_line
			(start -0.3048 -0.1016)
			(end 0.3048 -0.1016)
			(stroke
				(width 0.1)
				(type default)
			)
			(layer "B.Fab")
		)
		(fp_line
			(start 0.3048 0.9906)
			(end -0.3048 0.9906)
			(stroke
				(width 0.1)
				(type default)
			)
			(layer "B.Fab")
		)
		(fp_line
			(start -0.3048 0.9906)
			(end -0.3048 -0.1016)
			(stroke
				(width 0.1)
				(type default)
			)
			(layer "B.Fab")
		)
		(pad "1" smd rect
			(at 0 0 270)
			(size 0.508 0.508)
			(layers "B.Cu" "B.Mask" "B.Paste")
			(net "P3V3_STBY_MNG_RGMII")
		)
		(pad "2" smd rect
			(at 0 0.889 270)
			(size 0.508 0.508)
			(layers "B.Cu" "B.Mask" "B.Paste")
			(net "GND")
		)
		(zone
			(layer "B.Cu")
			(hatch none 0.5)
			(connect_pads
				(clearance 0)
			)
			(min_thickness 0.25)
			(keepout
				(tracks allowed)
				(vias not_allowed)
				(pads allowed)
				(copperpour not_allowed)
				(footprints allowed)
			)
			(placement
				(enabled no)
				(sheetname "")
			)
			(fill
				(thermal_gap 0.5)
				(thermal_bridge_width 0.5)
				(island_removal_mode 0)
			)
			(polygon
				(pts
					(xy 474.67266 -31.10992) (xy 474.67266 -30.60192) (xy 475.05366 -30.60192) (xy 475.05366 -31.10992)
				)
			)
		)
		(zone
			(layer "B.Cu")
			(hatch none 0.5)
			(connect_pads
				(clearance 0)
			)
			(min_thickness 0.25)
			(keepout
				(tracks not_allowed)
				(vias allowed)
				(pads allowed)
				(copperpour not_allowed)
				(footprints allowed)
			)
			(placement
				(enabled no)
				(sheetname "")
			)
			(fill
				(thermal_gap 0.5)
				(thermal_bridge_width 0.5)
				(island_removal_mode 0)
			)
			(polygon
				(pts
					(xy 475.05366 -31.10992) (xy 475.05366 -30.60192) (xy 474.67266 -30.60192) (xy 474.67266 -31.10992)
				)
			)
		)
	)
	(footprint ""
		(layer "B.Cu")
		(at 426.9105 -11.176 90)
		(property "Reference" "R2U49"
			(at 0 0 90)
			(layer "B.SilkS")
			(hide yes)
			(effects
				(font
					(size 1.27 1.27)
				)
				(justify mirror)
			)
		)
		(property "Value" ""
			(at 0 0 90)
			(layer "B.Fab")
			(effects
				(font
					(size 1.27 1.27)
				)
				(justify mirror)
			)
		)
		(duplicate_pad_numbers_are_jumpers no)
		(fp_poly
			(pts
				(xy 0.2794 -0.1016) (xy -0.2794 -0.1016) (xy -0.2794 0.9906) (xy 0.2794 0.9906)
			)
			(stroke
				(width 0)
				(type default)
			)
			(fill no)
			(layer "B.CrtYd")
		)
		(fp_line
			(start 0.2794 -0.1016)
			(end 0.2794 0.9906)
			(stroke
				(width 0.1)
				(type default)
			)
			(layer "B.Fab")
		)
		(fp_line
			(start -0.2794 -0.1016)
			(end 0.2794 -0.1016)
			(stroke
				(width 0.1)
				(type default)
			)
			(layer "B.Fab")
		)
		(fp_line
			(start 0.2794 0.9906)
			(end -0.2794 0.9906)
			(stroke
				(width 0.1)
				(type default)
			)
			(layer "B.Fab")
		)
		(fp_line
			(start -0.2794 0.9906)
			(end -0.2794 -0.1016)
			(stroke
				(width 0.1)
				(type default)
			)
			(layer "B.Fab")
		)
		(pad "1" smd rect
			(at 0 0 270)
			(size 0.508 0.508)
			(layers "B.Cu" "B.Mask" "B.Paste")
			(net "H_CPU0_MEMABC_MEMHOT_G_PCH_N")
		)
		(pad "2" smd rect
			(at 0 0.889 270)
			(size 0.508 0.508)
			(layers "B.Cu" "B.Mask" "B.Paste")
			(net "H_CPU0_MEMABC_MEMHOT_LVT3_K_N")
		)
		(zone
			(layer "B.Cu")
			(hatch none 0.5)
			(connect_pads
				(clearance 0)
			)
			(min_thickness 0.25)
			(keepout
				(tracks allowed)
				(vias not_allowed)
				(pads allowed)
				(copperpour not_allowed)
				(footprints allowed)
			)
			(placement
				(enabled no)
				(sheetname "")
			)
			(fill
				(thermal_gap 0.5)
				(thermal_bridge_width 0.5)
				(island_removal_mode 0)
			)
			(polygon
				(pts
					(xy 427.1645 -11.43) (xy 427.1645 -10.922) (xy 427.5455 -10.922) (xy 427.5455 -11.43)
				)
			)
		)
		(zone
			(layer "B.Cu")
			(hatch none 0.5)
			(connect_pads
				(clearance 0)
			)
			(min_thickness 0.25)
			(keepout
				(tracks not_allowed)
				(vias allowed)
				(pads allowed)
				(copperpour not_allowed)
				(footprints allowed)
			)
			(placement
				(enabled no)
				(sheetname "")
			)
			(fill
				(thermal_gap 0.5)
				(thermal_bridge_width 0.5)
				(island_removal_mode 0)
			)
			(polygon
				(pts
					(xy 427.5455 -11.43) (xy 427.5455 -10.922) (xy 427.1645 -10.922) (xy 427.1645 -11.43)
				)
			)
		)
	)
)
